# BASEBOARD_FAB2 (Tioga Pass) — schematic netlist excerpt (pin names and nets, part order shuffled) for the footprints in the layout excerpt that follows; sources: Cadence DE-HDL packaged netlist, KiCad conversion of Wiwynn_Tioga_Pass_MB.brd

C8W6  CAP_A  0.01UF 25V 10% X7R  pkg 0402V  page 245 : A = P3V3_STBY ; B = GND
R3P7  RES  1.00K 1% EMPTY  pkg 0402  page 133 : A = P1V05_PCH_STBY ; B = FM_PRSNT_2_1_N
CT10  CAP  1000PF 50V 10% X7R  pkg 0402LF  page 227 : A = A_TSENSE_PVDDQ_KLM ; B = GND

(kicad_pcb
	(version 20260206)
	(generator "pcbnew")
	(generator_version "10.0")
	(general
		(thickness 1.6)
		(legacy_teardrops no)
	)
	(paper "A4")
	(title_block
		(title "Wiwynn_Tioga_Pass_MB.brd")
		(comment 1 "Tioga Pass / footprints 3800-3802 of 4770")
	)
	(layers
		(0 "F.Cu" signal "TOP")
		(4 "In1.Cu" signal "L2GND")
		(6 "In2.Cu" signal "L3")
		(8 "In3.Cu" signal "L4GND")
		(10 "In4.Cu" signal "L5")
		(12 "In5.Cu" signal "L6GND")
		(14 "In6.Cu" signal "L7VCC")
		(16 "In7.Cu" signal "L8VCC")
		(18 "In8.Cu" signal "L9GND")
		(20 "In9.Cu" signal "L10")
		(22 "In10.Cu" signal "L11GND")
		(24 "In11.Cu" signal "L12")
		(26 "In12.Cu" signal "L13GND")
		(2 "B.Cu" signal "BOTTOM")
		(9 "F.Adhes" user "F.Adhesive")
		(11 "B.Adhes" user "B.Adhesive")
		(13 "F.Paste" user "Package Geometry/Pastemask Top")
		(15 "B.Paste" user "Package Geometry/Pastemask Bottom")
		(5 "F.SilkS" user "Ref Des/Silkscreen Top")
		(7 "B.SilkS" user "Ref Des/Silkscreen Bottom")
		(1 "F.Mask" user "Board Geometry/Soldermask Top")
		(3 "B.Mask" user "Board Geometry/Soldermask Bottom")
		(17 "Dwgs.User" user "User.Drawings")
		(19 "Cmts.User" user "User.Comments")
		(21 "Eco1.User" user "User.Eco1")
		(23 "Eco2.User" user "User.Eco2")
		(25 "Edge.Cuts" user "Board Geometry/Outline")
		(27 "Margin" user)
		(31 "F.CrtYd" user "Package Geometry/Place Bound Top")
		(29 "B.CrtYd" user "Package Geometry/Place Bound Bottom")
		(35 "F.Fab" user "Ref Des/Assembly Top")
		(33 "B.Fab" user "Ref Des/Assembly Bottom")
	)
	(footprint ""
		(layer "B.Cu")
		(at -1.3335 -145.8214 90)
		(property "Reference" "CT10"
			(at 0.8382 -0.84963 90)
			(unlocked yes)
			(layer "B.SilkS")
			(effects
				(font
					(size 0.7874 0.5842)
					(thickness 0.1524)
				)
				(justify left mirror)
			)
		)
		(property "Value" ""
			(at 0 0 90)
			(layer "B.Fab")
			(effects
				(font
					(size 1.27 1.27)
				)
				(justify mirror)
			)
		)
		(duplicate_pad_numbers_are_jumpers no)
		(fp_poly
			(pts
				(xy -0.3048 -0.1016) (xy -0.3048 0.9906) (xy 0.3048 0.9906) (xy 0.3048 -0.1016)
			)
			(stroke
				(width 0)
				(type default)
			)
			(fill no)
			(layer "B.CrtYd")
		)
		(fp_line
			(start 0.3048 -0.1016)
			(end 0.3048 0.9906)
			(stroke
				(width 0.1)
				(type default)
			)
			(layer "B.Fab")
		)
		(fp_line
			(start -0.3048 -0.1016)
			(end 0.3048 -0.1016)
			(stroke
				(width 0.1)
				(type default)
			)
			(layer "B.Fab")
		)
		(fp_line
			(start 0.3048 0.9906)
			(end -0.3048 0.9906)
			(stroke
				(width 0.1)
				(type default)
			)
			(layer "B.Fab")
		)
		(fp_line
			(start -0.3048 0.9906)
			(end -0.3048 -0.1016)
			(stroke
				(width 0.1)
				(type default)
			)
			(layer "B.Fab")
		)
		(pad "1" smd rect
			(at 0 0 270)
			(size 0.508 0.508)
			(layers "B.Cu" "B.Mask" "B.Paste")
			(net "A_TSENSE_PVDDQ_KLM")
		)
		(pad "2" smd rect
			(at 0 0.889 270)
			(size 0.508 0.508)
			(layers "B.Cu" "B.Mask" "B.Paste")
			(net "GND")
		)
		(zone
			(layer "B.Cu")
			(hatch none 0.5)
			(connect_pads
				(clearance 0)
			)
			(min_thickness 0.25)
			(keepout
				(tracks allowed)
				(vias not_allowed)
				(pads allowed)
				(copperpour not_allowed)
				(footprints allowed)
			)
			(placement
				(enabled no)
				(sheetname "")
			)
			(fill
				(thermal_gap 0.5)
				(thermal_bridge_width 0.5)
				(island_removal_mode 0)
			)
			(polygon
				(pts
					(xy -1.0795 -146.0754) (xy -1.0795 -145.5674) (xy -0.6985 -145.5674) (xy -0.6985 -146.0754)
				)
			)
		)
		(zone
			(layer "B.Cu")
			(hatch none 0.5)
			(connect_pads
				(clearance 0)
			)
			(min_thickness 0.25)
			(keepout
				(tracks not_allowed)
				(vias allowed)
				(pads allowed)
				(copperpour not_allowed)
				(footprints allowed)
			)
			(placement
				(enabled no)
				(sheetname "")
			)
			(fill
				(thermal_gap 0.5)
				(thermal_bridge_width 0.5)
				(island_removal_mode 0)
			)
			(polygon
				(pts
					(xy -0.6985 -146.0754) (xy -0.6985 -145.5674) (xy -1.0795 -145.5674) (xy -1.0795 -146.0754)
				)
			)
		)
	)
	(footprint ""
		(layer "B.Cu")
		(at 382.397 -2.448814)
		(property "Reference" "C8W6"
			(at 0.8382 -0.67818 0)
			(unlocked yes)
			(layer "B.SilkS")
			(effects
				(font
					(size 0.4064 0.254)
					(thickness 0.1524)
				)
				(justify left mirror)
			)
		)
		(property "Value" ""
			(at 0 0 0)
			(layer "B.Fab")
			(effects
				(font
					(size 1.27 1.27)
				)
				(justify mirror)
			)
		)
		(duplicate_pad_numbers_are_jumpers no)
		(fp_poly
			(pts
				(xy -0.3048 -0.1016) (xy -0.3048 0.9906) (xy 0.3048 0.9906) (xy 0.3048 -0.1016)
			)
			(stroke
				(width 0)
				(type default)
			)
			(fill no)
			(layer "B.CrtYd")
		)
		(fp_line
			(start -0.3048 -0.1016)
			(end 0.3048 -0.1016)
			(stroke
				(width 0.1)
				(type default)
			)
			(layer "B.Fab")
		)
		(fp_line
			(start -0.3048 0.9906)
			(end -0.3048 -0.1016)
			(stroke
				(width 0.1)
				(type default)
			)
			(layer "B.Fab")
		)
		(fp_line
			(start 0.3048 -0.1016)
			(end 0.3048 0.9906)
			(stroke
				(width 0.1)
				(type default)
			)
			(layer "B.Fab")
		)
		(fp_line
			(start 0.3048 0.9906)
			(end -0.3048 0.9906)
			(stroke
				(width 0.1)
				(type default)
			)
			(layer "B.Fab")
		)
		(pad "1" smd rect
			(at 0 0 180)
			(size 0.508 0.508)
			(layers "B.Cu" "B.Mask" "B.Paste")
			(net "P3V3_STBY")
		)
		(pad "2" smd rect
			(at 0 0.889 180)
			(size 0.508 0.508)
			(layers "B.Cu" "B.Mask" "B.Paste")
			(net "GND")
		)
		(zone
			(layer "B.Cu")
			(hatch none 0.5)
			(connect_pads
				(clearance 0)
			)
			(min_thickness 0.25)
			(keepout
				(tracks allowed)
				(vias not_allowed)
				(pads allowed)
				(copperpour not_allowed)
				(footprints allowed)
			)
			(placement
				(enabled no)
				(sheetname "")
			)
			(fill
				(thermal_gap 0.5)
				(thermal_bridge_width 0.5)
				(island_removal_mode 0)
			)
			(polygon
				(pts
					(xy 382.651 -2.194814) (xy 382.143 -2.194814) (xy 382.143 -1.813814) (xy 382.651 -1.813814)
				)
			)
		)
		(zone
			(layer "B.Cu")
			(hatch none 0.5)
			(connect_pads
				(clearance 0)
			)
			(min_thickness 0.25)
			(keepout
				(tracks not_allowed)
				(vias allowed)
				(pads allowed)
				(copperpour not_allowed)
				(footprints allowed)
			)
			(placement
				(enabled no)
				(sheetname "")
			)
			(fill
				(thermal_gap 0.5)
				(thermal_bridge_width 0.5)
				(island_removal_mode 0)
			)
			(polygon
				(pts
					(xy 382.651 -1.813814) (xy 382.143 -1.813814) (xy 382.143 -2.194814) (xy 382.651 -2.194814)
				)
			)
		)
	)
	(footprint ""
		(layer "B.Cu")
		(at 370.156994 -93.915992 -90)
		(property "Reference" "R3P7"
			(at 0 0 90)
			(layer "B.SilkS")
			(hide yes)
			(effects
				(font
					(size 1.27 1.27)
				)
				(justify mirror)
			)
		)
		(property "Value" ""
			(at 0 0 90)
			(layer "B.Fab")
			(effects
				(font
					(size 1.27 1.27)
				)
				(justify mirror)
			)
		)
		(duplicate_pad_numbers_are_jumpers no)
		(fp_poly
			(pts
				(xy 0.2794 -0.1016) (xy -0.2794 -0.1016) (xy -0.2794 0.9906) (xy 0.2794 0.9906)
			)
			(stroke
				(width 0)
				(type default)
			)
			(fill no)
			(layer "B.CrtYd")
		)
		(fp_line
			(start -0.2794 0.9906)
			(end -0.2794 -0.1016)
			(stroke
				(width 0.1)
				(type default)
			)
			(layer "B.Fab")
		)
		(fp_line
			(start 0.2794 0.9906)
			(end -0.2794 0.9906)
			(stroke
				(width 0.1)
				(type default)
			)
			(layer "B.Fab")
		)
		(fp_line
			(start -0.2794 -0.1016)
			(end 0.2794 -0.1016)
			(stroke
				(width 0.1)
				(type default)
			)
			(layer "B.Fab")
		)
		(fp_line
			(start 0.2794 -0.1016)
			(end 0.2794 0.9906)
			(stroke
				(width 0.1)
				(type default)
			)
			(layer "B.Fab")
		)
		(pad "1" smd rect
			(at 0 0 90)
			(size 0.508 0.508)
			(layers "B.Cu" "B.Mask" "B.Paste")
			(net "P1V05_PCH_STBY")
		)
		(pad "2" smd rect
			(at 0 0.889 90)
			(size 0.508 0.508)
			(layers "B.Cu" "B.Mask" "B.Paste")
			(net "FM_PRSNT_2_1_N")
		)
		(zone
			(layer "B.Cu")
			(hatch none 0.5)
			(connect_pads
				(clearance 0)
			)
			(min_thickness 0.25)
			(keepout
				(tracks not_allowed)
				(vias allowed)
				(pads allowed)
				(copperpour not_allowed)
				(footprints allowed)
			)
			(placement
				(enabled no)
				(sheetname "")
			)
			(fill
				(thermal_gap 0.5)
				(thermal_bridge_width 0.5)
				(island_removal_mode 0)
			)
			(polygon
				(pts
					(xy 369.521994 -93.661992) (xy 369.521994 -94.169992) (xy 369.902994 -94.169992) (xy 369.902994 -93.661992)
				)
			)
		)
		(zone
			(layer "B.Cu")
			(hatch none 0.5)
			(connect_pads
				(clearance 0)
			)
			(min_thickness 0.25)
			(keepout
				(tracks allowed)
				(vias not_allowed)
				(pads allowed)
				(copperpour not_allowed)
				(footprints allowed)
			)
			(placement
				(enabled no)
				(sheetname "")
			)
			(fill
				(thermal_gap 0.5)
				(thermal_bridge_width 0.5)
				(island_removal_mode 0)
			)
			(polygon
				(pts
					(xy 369.902994 -93.661992) (xy 369.902994 -94.169992) (xy 369.521994 -94.169992) (xy 369.521994 -93.661992)
				)
			)
		)
	)
)
